(kicad_pcb
	(version 20260206)
	(generator "pcbnew")
	(generator_version "10.0")
	(general
		(thickness 1.6)
		(legacy_teardrops no)
	)
	(paper "A4")
	(title_block
		(title "01162023_DA0F0TEBIF0_F0T_Expander_BD_F_brd_V02_OCP.brd")
		(comment 1 "Grand Teton / footprints 3226-3231 of 9728")
	)
	(layers
		(0 "F.Cu" signal "TOP")
		(4 "In1.Cu" signal "GND")
		(6 "In2.Cu" signal "VCC")
		(8 "In3.Cu" signal "VCC1")
		(10 "In4.Cu" signal "GND1")
		(12 "In5.Cu" signal "IN1")
		(14 "In6.Cu" signal "GND2")
		(16 "In7.Cu" signal "IN2")
		(18 "In8.Cu" signal "GND3")
		(20 "In9.Cu" signal "IN3")
		(22 "In10.Cu" signal "GND4")
		(24 "In11.Cu" signal "IN4")
		(26 "In12.Cu" signal "GND5")
		(28 "In13.Cu" signal "IN5")
		(30 "In14.Cu" signal "GND6")
		(32 "In15.Cu" signal "IN6")
		(34 "In16.Cu" signal "GND7")
		(2 "B.Cu" signal "BOTTOM")
		(9 "F.Adhes" user "F.Adhesive")
		(11 "B.Adhes" user "B.Adhesive")
		(13 "F.Paste" user "Package Geometry/Pastemask Top")
		(15 "B.Paste" user "Package Geometry/Pastemask Bottom")
		(5 "F.SilkS" user "Ref Des/Silkscreen Top")
		(7 "B.SilkS" user "Ref Des/Silkscreen Bottom")
		(1 "F.Mask" user "Board Geometry/Soldermask Top")
		(3 "B.Mask" user "Board Geometry/Soldermask Bottom")
		(17 "Dwgs.User" user "User.Drawings")
		(19 "Cmts.User" user "User.Comments")
		(21 "Eco1.User" user "User.Eco1")
		(23 "Eco2.User" user "User.Eco2")
		(25 "Edge.Cuts" user "Board Geometry/Outline")
		(27 "Margin" user)
		(31 "F.CrtYd" user "Package Geometry/Place Bound Top")
		(29 "B.CrtYd" user "Package Geometry/Place Bound Bottom")
		(35 "F.Fab" user "Ref Des/Assembly Top")
		(33 "B.Fab" user "Ref Des/Assembly Bottom")
	)
	(footprint ""
		(layer "F.Cu")
		(at 251.979684 -225.49993 180)
		(property "Reference" "U319"
			(at 0.468884 -6.9088 0)
			(unlocked yes)
			(layer "F.SilkS")
			(effects
				(font
					(size 0.7874 0.5842)
					(thickness 0.1524)
				)
				(justify left)
			)
		)
		(property "Value" ""
			(at 0 0 180)
			(layer "F.Fab")
			(effects
				(font
					(size 1.27 1.27)
				)
			)
		)
		(duplicate_pad_numbers_are_jumpers no)
		(fp_line
			(start 3.795014 5.2451)
			(end 3.795014 -5.2451)
			(stroke
				(width 0.1524)
				(type default)
			)
			(layer "F.SilkS")
		)
		(fp_line
			(start 3.795014 -5.2451)
			(end 1.9431 -5.2451)
			(stroke
				(width 0.1524)
				(type default)
			)
			(layer "F.SilkS")
		)
		(fp_line
			(start 1.9431 -5.2451)
			(end 0 -3.302)
			(stroke
				(width 0.1524)
				(type default)
			)
			(layer "F.SilkS")
		)
		(fp_line
			(start 0 -3.302)
			(end -1.9431 -5.2451)
			(stroke
				(width 0.1524)
				(type default)
			)
			(layer "F.SilkS")
		)
		(fp_line
			(start -1.9431 -5.2451)
			(end -3.795014 -5.2451)
			(stroke
				(width 0.1524)
				(type default)
			)
			(layer "F.SilkS")
		)
		(fp_line
			(start -3.795014 5.2451)
			(end 3.795014 5.2451)
			(stroke
				(width 0.1524)
				(type default)
			)
			(layer "F.SilkS")
		)
		(fp_line
			(start -3.795014 -5.2451)
			(end -3.795014 5.2451)
			(stroke
				(width 0.1524)
				(type default)
			)
			(layer "F.SilkS")
		)
		(fp_poly
			(pts
				(xy -5.976366 -4.445) (xy -7.239 -3.81381) (xy -7.239 -5.07619)
			)
			(stroke
				(width 0)
				(type default)
			)
			(fill yes)
			(layer "F.SilkS")
		)
		(fp_line
			(start 3.795014 5.2451)
			(end 3.795014 -5.2451)
			(stroke
				(width 0.1)
				(type default)
			)
			(layer "F.Fab")
		)
		(fp_line
			(start 3.795014 -5.2451)
			(end -3.795014 -5.2451)
			(stroke
				(width 0.1)
				(type default)
			)
			(layer "F.Fab")
		)
		(fp_line
			(start -3.795014 5.2451)
			(end 3.795014 5.2451)
			(stroke
				(width 0.1)
				(type default)
			)
			(layer "F.Fab")
		)
		(fp_line
			(start -3.795014 -5.2451)
			(end -3.795014 5.2451)
			(stroke
				(width 0.1)
				(type default)
			)
			(layer "F.Fab")
		)
		(fp_poly
			(pts
				(xy -5.976366 -4.445) (xy -7.239 -3.81381) (xy -7.239 -5.07619)
			)
			(stroke
				(width 0)
				(type default)
			)
			(fill yes)
			(layer "F.Fab")
		)
		(pad "1" smd rect
			(at -4.880102 -4.445 90)
			(size 0.8128 1.905)
			(layers "F.Cu" "F.Mask" "F.Paste")
			(net "SPI_PEX2_SDIO3_R1")
		)
		(pad "2" smd rect
			(at -4.880102 -3.175 90)
			(size 0.8128 1.905)
			(layers "F.Cu" "F.Mask" "F.Paste")
			(net "P1V8_PEX")
		)
		(pad "3" smd rect
			(at -4.880102 -1.905 90)
			(size 0.8128 1.905)
			(layers "F.Cu" "F.Mask" "F.Paste")
			(net "SPI_PEX2_RST_R_N")
		)
		(pad "4" smd rect
			(at -4.880102 -0.635 90)
			(size 0.8128 1.905)
			(layers "F.Cu" "F.Mask" "F.Paste")
			(net "Net_9014")
		)
		(pad "5" smd rect
			(at -4.880102 0.635 90)
			(size 0.8128 1.905)
			(layers "F.Cu" "F.Mask" "F.Paste")
			(net "Net_9013")
		)
		(pad "6" smd rect
			(at -4.880102 1.905 90)
			(size 0.8128 1.905)
			(layers "F.Cu" "F.Mask" "F.Paste")
			(net "Net_9012")
		)
		(pad "7" smd rect
			(at -4.880102 3.175 90)
			(size 0.8128 1.905)
			(layers "F.Cu" "F.Mask" "F.Paste")
			(net "SPI_PEX2_CS_MUX_R_N")
		)
		(pad "8" smd rect
			(at -4.880102 4.445 90)
			(size 0.8128 1.905)
			(layers "F.Cu" "F.Mask" "F.Paste")
			(net "SPI_PEX2_SDIO1_MUX_R")
		)
		(pad "9" smd rect
			(at 4.880102 4.445 270)
			(size 0.8128 1.905)
			(layers "F.Cu" "F.Mask" "F.Paste")
			(net "SPI_PEX2_SDIO2_R1")
		)
		(pad "10" smd rect
			(at 4.880102 3.175 270)
			(size 0.8128 1.905)
			(layers "F.Cu" "F.Mask" "F.Paste")
			(net "GND")
		)
		(pad "11" smd rect
			(at 4.880102 1.905 270)
			(size 0.8128 1.905)
			(layers "F.Cu" "F.Mask" "F.Paste")
			(net "Net_9011")
		)
		(pad "12" smd rect
			(at 4.880102 0.635 270)
			(size 0.8128 1.905)
			(layers "F.Cu" "F.Mask" "F.Paste")
			(net "Net_9010")
		)
		(pad "13" smd rect
			(at 4.880102 -0.635 270)
			(size 0.8128 1.905)
			(layers "F.Cu" "F.Mask" "F.Paste")
			(net "Net_9009")
		)
		(pad "14" smd rect
			(at 4.880102 -1.905 270)
			(size 0.8128 1.905)
			(layers "F.Cu" "F.Mask" "F.Paste")
			(net "Net_9008")
		)
		(pad "15" smd rect
			(at 4.880102 -3.175 270)
			(size 0.8128 1.905)
			(layers "F.Cu" "F.Mask" "F.Paste")
			(net "SPI_PEX2_SDIO0_MUX_R")
		)
		(pad "16" smd rect
			(at 4.880102 -4.445 270)
			(size 0.8128 1.905)
			(layers "F.Cu" "F.Mask" "F.Paste")
			(net "SPI_PEX2_CLK_MUX_R")
		)
	)
	(footprint ""
		(layer "F.Cu")
		(at 362.462826 -111.377476 -90)
		(property "Reference" "PR7104"
			(at 0 0 270)
			(layer "F.SilkS")
			(hide yes)
			(effects
				(font
					(size 1.27 1.27)
				)
			)
		)
		(property "Value" ""
			(at 0 0 270)
			(layer "F.Fab")
			(effects
				(font
					(size 1.27 1.27)
				)
			)
		)
		(duplicate_pad_numbers_are_jumpers no)
		(fp_line
			(start -0.7874 0.4064)
			(end -0.7874 -0.4064)
			(stroke
				(width 0.1524)
				(type default)
			)
			(layer "F.SilkS")
		)
		(fp_line
			(start 0.7874 0.4064)
			(end -0.7874 0.4064)
			(stroke
				(width 0.1524)
				(type default)
			)
			(layer "F.SilkS")
		)
		(fp_line
			(start -0.7874 -0.4064)
			(end 0.7874 -0.4064)
			(stroke
				(width 0.1524)
				(type default)
			)
			(layer "F.SilkS")
		)
		(fp_line
			(start 0.7874 -0.4064)
			(end 0.7874 0.4064)
			(stroke
				(width 0.1524)
				(type default)
			)
			(layer "F.SilkS")
		)
		(fp_line
			(start -0.67945 0.3048)
			(end -0.67945 -0.305054)
			(stroke
				(width 0.1)
				(type default)
			)
			(layer "F.Fab")
		)
		(fp_line
			(start -0.12065 0.3048)
			(end -0.67945 0.3048)
			(stroke
				(width 0.1)
				(type default)
			)
			(layer "F.Fab")
		)
		(fp_line
			(start 0.120396 0.3048)
			(end 0.120396 0.2794)
			(stroke
				(width 0.1)
				(type default)
			)
			(layer "F.Fab")
		)
		(fp_line
			(start 0.67945 0.3048)
			(end 0.120396 0.3048)
			(stroke
				(width 0.1)
				(type default)
			)
			(layer "F.Fab")
		)
		(fp_line
			(start -0.12065 0.2794)
			(end -0.12065 0.3048)
			(stroke
				(width 0.1)
				(type default)
			)
			(layer "F.Fab")
		)
		(fp_line
			(start 0.120396 0.2794)
			(end -0.12065 0.2794)
			(stroke
				(width 0.1)
				(type default)
			)
			(layer "F.Fab")
		)
		(fp_line
			(start -0.12065 -0.2794)
			(end 0.12065 -0.2794)
			(stroke
				(width 0.1)
				(type default)
			)
			(layer "F.Fab")
		)
		(fp_line
			(start 0.12065 -0.2794)
			(end 0.12065 -0.3048)
			(stroke
				(width 0.1)
				(type default)
			)
			(layer "F.Fab")
		)
		(fp_line
			(start 0.12065 -0.3048)
			(end 0.67945 -0.3048)
			(stroke
				(width 0.1)
				(type default)
			)
			(layer "F.Fab")
		)
		(fp_line
			(start 0.67945 -0.3048)
			(end 0.67945 0.3048)
			(stroke
				(width 0.1)
				(type default)
			)
			(layer "F.Fab")
		)
		(fp_line
			(start -0.67945 -0.305054)
			(end -0.12065 -0.305054)
			(stroke
				(width 0.1)
				(type default)
			)
			(layer "F.Fab")
		)
		(fp_line
			(start -0.12065 -0.305054)
			(end -0.12065 -0.2794)
			(stroke
				(width 0.1)
				(type default)
			)
			(layer "F.Fab")
		)
		(pad "1" smd circle
			(at -0.40005 0 270)
			(size 0 0)
			(layers "F.Cu" "F.Mask" "F.Paste")
			(net "P3V3_NIC6_CO_ILIMIT")
		)
		(pad "2" smd circle
			(at 0.40005 0 270)
			(size 0 0)
			(layers "F.Cu" "F.Mask" "F.Paste")
			(net "GND")
		)
	)
	(footprint ""
		(layer "F.Cu")
		(at 341.870792 -240.691162 90)
		(property "Reference" "R3581"
			(at 0 0 90)
			(layer "F.SilkS")
			(hide yes)
			(effects
				(font
					(size 1.27 1.27)
				)
			)
		)
		(property "Value" ""
			(at 0 0 90)
			(layer "F.Fab")
			(effects
				(font
					(size 1.27 1.27)
				)
			)
		)
		(duplicate_pad_numbers_are_jumpers no)
		(fp_line
			(start 0.7874 -0.4064)
			(end 0.7874 0.4064)
			(stroke
				(width 0.1524)
				(type default)
			)
			(layer "F.SilkS")
		)
		(fp_line
			(start -0.7874 -0.4064)
			(end 0.7874 -0.4064)
			(stroke
				(width 0.1524)
				(type default)
			)
			(layer "F.SilkS")
		)
		(fp_line
			(start 0.7874 0.4064)
			(end -0.7874 0.4064)
			(stroke
				(width 0.1524)
				(type default)
			)
			(layer "F.SilkS")
		)
		(fp_line
			(start -0.7874 0.4064)
			(end -0.7874 -0.4064)
			(stroke
				(width 0.1524)
				(type default)
			)
			(layer "F.SilkS")
		)
		(fp_line
			(start -0.12065 -0.305054)
			(end -0.12065 -0.2794)
			(stroke
				(width 0.1)
				(type default)
			)
			(layer "F.Fab")
		)
		(fp_line
			(start -0.67945 -0.305054)
			(end -0.12065 -0.305054)
			(stroke
				(width 0.1)
				(type default)
			)
			(layer "F.Fab")
		)
		(fp_line
			(start 0.67945 -0.3048)
			(end 0.67945 0.3048)
			(stroke
				(width 0.1)
				(type default)
			)
			(layer "F.Fab")
		)
		(fp_line
			(start 0.12065 -0.3048)
			(end 0.67945 -0.3048)
			(stroke
				(width 0.1)
				(type default)
			)
			(layer "F.Fab")
		)
		(fp_line
			(start 0.12065 -0.2794)
			(end 0.12065 -0.3048)
			(stroke
				(width 0.1)
				(type default)
			)
			(layer "F.Fab")
		)
		(fp_line
			(start -0.12065 -0.2794)
			(end 0.12065 -0.2794)
			(stroke
				(width 0.1)
				(type default)
			)
			(layer "F.Fab")
		)
		(fp_line
			(start 0.120396 0.2794)
			(end -0.12065 0.2794)
			(stroke
				(width 0.1)
				(type default)
			)
			(layer "F.Fab")
		)
		(fp_line
			(start -0.12065 0.2794)
			(end -0.12065 0.3048)
			(stroke
				(width 0.1)
				(type default)
			)
			(layer "F.Fab")
		)
		(fp_line
			(start 0.67945 0.3048)
			(end 0.120396 0.3048)
			(stroke
				(width 0.1)
				(type default)
			)
			(layer "F.Fab")
		)
		(fp_line
			(start 0.120396 0.3048)
			(end 0.120396 0.2794)
			(stroke
				(width 0.1)
				(type default)
			)
			(layer "F.Fab")
		)
		(fp_line
			(start -0.12065 0.3048)
			(end -0.67945 0.3048)
			(stroke
				(width 0.1)
				(type default)
			)
			(layer "F.Fab")
		)
		(fp_line
			(start -0.67945 0.3048)
			(end -0.67945 -0.305054)
			(stroke
				(width 0.1)
				(type default)
			)
			(layer "F.Fab")
		)
		(pad "1" smd circle
			(at -0.40005 0 90)
			(size 0 0)
			(layers "F.Cu" "F.Mask" "F.Paste")
			(net "SSD0_PWR_EN")
		)
		(pad "2" smd circle
			(at 0.40005 0 90)
			(size 0 0)
			(layers "F.Cu" "F.Mask" "F.Paste")
			(net "SSD0_PWR_EN_R")
		)
	)
	(footprint ""
		(layer "F.Cu")
		(at 452.472806 -254.5969 -90)
		(property "Reference" "C4411"
			(at 0 0 270)
			(layer "F.SilkS")
			(hide yes)
			(effects
				(font
					(size 1.27 1.27)
				)
			)
		)
		(property "Value" ""
			(at 0 0 270)
			(layer "F.Fab")
			(effects
				(font
					(size 1.27 1.27)
				)
			)
		)
		(duplicate_pad_numbers_are_jumpers no)
		(fp_line
			(start -1.2954 0.5842)
			(end -1.2954 -0.5842)
			(stroke
				(width 0.1524)
				(type default)
			)
			(layer "F.SilkS")
		)
		(fp_line
			(start 1.2954 0.5842)
			(end -1.2954 0.5842)
			(stroke
				(width 0.1524)
				(type default)
			)
			(layer "F.SilkS")
		)
		(fp_line
			(start -1.2954 -0.5842)
			(end 1.2954 -0.5842)
			(stroke
				(width 0.1524)
				(type default)
			)
			(layer "F.SilkS")
		)
		(fp_line
			(start 1.2954 -0.5842)
			(end 1.2954 0.5842)
			(stroke
				(width 0.1524)
				(type default)
			)
			(layer "F.SilkS")
		)
		(fp_line
			(start -0.8636 0.4572)
			(end -0.8636 0.4064)
			(stroke
				(width 0.1)
				(type default)
			)
			(layer "F.Fab")
		)
		(fp_line
			(start 0.8636 0.4572)
			(end -0.8636 0.4572)
			(stroke
				(width 0.1)
				(type default)
			)
			(layer "F.Fab")
		)
		(fp_line
			(start -1.1938 0.4064)
			(end -1.1938 -0.4064)
			(stroke
				(width 0.1)
				(type default)
			)
			(layer "F.Fab")
		)
		(fp_line
			(start -0.8636 0.4064)
			(end -1.1938 0.4064)
			(stroke
				(width 0.1)
				(type default)
			)
			(layer "F.Fab")
		)
		(fp_line
			(start 0.8636 0.4064)
			(end 0.8636 0.4572)
			(stroke
				(width 0.1)
				(type default)
			)
			(layer "F.Fab")
		)
		(fp_line
			(start 1.1938 0.4064)
			(end 0.8636 0.4064)
			(stroke
				(width 0.1)
				(type default)
			)
			(layer "F.Fab")
		)
		(fp_line
			(start -1.1938 -0.4064)
			(end -0.8636 -0.4064)
			(stroke
				(width 0.1)
				(type default)
			)
			(layer "F.Fab")
		)
		(fp_line
			(start -0.8636 -0.4064)
			(end -0.8636 -0.4572)
			(stroke
				(width 0.1)
				(type default)
			)
			(layer "F.Fab")
		)
		(fp_line
			(start 0.8636 -0.4064)
			(end 1.1938 -0.4064)
			(stroke
				(width 0.1)
				(type default)
			)
			(layer "F.Fab")
		)
		(fp_line
			(start 1.1938 -0.4064)
			(end 1.1938 0.4064)
			(stroke
				(width 0.1)
				(type default)
			)
			(layer "F.Fab")
		)
		(fp_line
			(start -0.8636 -0.4572)
			(end 0.8636 -0.4572)
			(stroke
				(width 0.1)
				(type default)
			)
			(layer "F.Fab")
		)
		(fp_line
			(start 0.8636 -0.4572)
			(end 0.8636 -0.4064)
			(stroke
				(width 0.1)
				(type default)
			)
			(layer "F.Fab")
		)
		(pad "1" smd rect
			(at -0.7366 0 180)
			(size 0.7112 0.8128)
			(layers "F.Cu" "F.Mask" "F.Paste")
			(net "P1V25_SERDES_VDDPLL_PEX3_C9")
		)
		(pad "2" smd rect
			(at 0.7366 0 180)
			(size 0.7112 0.8128)
			(layers "F.Cu" "F.Mask" "F.Paste")
			(net "GND")
		)
	)
	(footprint ""
		(layer "F.Cu")
		(at 359.23474 -303.649634 90)
		(property "Reference" "PC197"
			(at 0 0 90)
			(layer "F.SilkS")
			(hide yes)
			(effects
				(font
					(size 1.27 1.27)
				)
			)
		)
		(property "Value" ""
			(at 0 0 90)
			(layer "F.Fab")
			(effects
				(font
					(size 1.27 1.27)
				)
			)
		)
		(duplicate_pad_numbers_are_jumpers no)
		(fp_line
			(start 1.524 -0.762)
			(end 1.524 0.762)
			(stroke
				(width 0.1524)
				(type default)
			)
			(layer "F.SilkS")
		)
		(fp_line
			(start -1.524 -0.762)
			(end 1.524 -0.762)
			(stroke
				(width 0.1524)
				(type default)
			)
			(layer "F.SilkS")
		)
		(fp_line
			(start 1.524 0.762)
			(end -1.524 0.762)
			(stroke
				(width 0.1524)
				(type default)
			)
			(layer "F.SilkS")
		)
		(fp_line
			(start -1.524 0.762)
			(end -1.524 -0.762)
			(stroke
				(width 0.1524)
				(type default)
			)
			(layer "F.SilkS")
		)
		(fp_line
			(start 1.1049 -0.724916)
			(end -1.1049 -0.724916)
			(stroke
				(width 0.1)
				(type default)
			)
			(layer "F.Fab")
		)
		(fp_line
			(start -1.1049 -0.724916)
			(end -1.1049 0.724916)
			(stroke
				(width 0.1)
				(type default)
			)
			(layer "F.Fab")
		)
		(fp_line
			(start 1.1049 0.724916)
			(end 1.1049 -0.724916)
			(stroke
				(width 0.1)
				(type default)
			)
			(layer "F.Fab")
		)
		(fp_line
			(start -1.1049 0.724916)
			(end 1.1049 0.724916)
			(stroke
				(width 0.1)
				(type default)
			)
			(layer "F.Fab")
		)
		(pad "1" smd rect
			(at -0.889 0 270)
			(size 1.016 1.27)
			(layers "F.Cu" "F.Mask" "F.Paste")
			(net "P0V8_PEX3")
		)
		(pad "2" smd rect
			(at 0.889 0 270)
			(size 1.016 1.27)
			(layers "F.Cu" "F.Mask" "F.Paste")
			(net "GND")
		)
	)
	(footprint ""
		(layer "F.Cu")
		(at 251.854716 -22.867366 90)
		(property "Reference" "C3934"
			(at 0 0 90)
			(layer "F.SilkS")
			(hide yes)
			(effects
				(font
					(size 1.27 1.27)
				)
			)
		)
		(property "Value" ""
			(at 0 0 90)
			(layer "F.Fab")
			(effects
				(font
					(size 1.27 1.27)
				)
			)
		)
		(duplicate_pad_numbers_are_jumpers no)
		(fp_line
			(start 0.7874 -0.4064)
			(end 0.7874 0.4064)
			(stroke
				(width 0.1524)
				(type default)
			)
			(layer "F.SilkS")
		)
		(fp_line
			(start -0.7874 -0.4064)
			(end 0.7874 -0.4064)
			(stroke
				(width 0.1524)
				(type default)
			)
			(layer "F.SilkS")
		)
		(fp_line
			(start 0.7874 0.4064)
			(end -0.7874 0.4064)
			(stroke
				(width 0.1524)
				(type default)
			)
			(layer "F.SilkS")
		)
		(fp_line
			(start -0.7874 0.4064)
			(end -0.7874 -0.4064)
			(stroke
				(width 0.1524)
				(type default)
			)
			(layer "F.SilkS")
		)
		(fp_line
			(start -0.12065 -0.305054)
			(end -0.12065 -0.2794)
			(stroke
				(width 0.1)
				(type default)
			)
			(layer "F.Fab")
		)
		(fp_line
			(start -0.67945 -0.305054)
			(end -0.12065 -0.305054)
			(stroke
				(width 0.1)
				(type default)
			)
			(layer "F.Fab")
		)
		(fp_line
			(start 0.67945 -0.3048)
			(end 0.67945 0.3048)
			(stroke
				(width 0.1)
				(type default)
			)
			(layer "F.Fab")
		)
		(fp_line
			(start 0.12065 -0.3048)
			(end 0.67945 -0.3048)
			(stroke
				(width 0.1)
				(type default)
			)
			(layer "F.Fab")
		)
		(fp_line
			(start 0.12065 -0.2794)
			(end 0.12065 -0.3048)
			(stroke
				(width 0.1)
				(type default)
			)
			(layer "F.Fab")
		)
		(fp_line
			(start -0.12065 -0.2794)
			(end 0.12065 -0.2794)
			(stroke
				(width 0.1)
				(type default)
			)
			(layer "F.Fab")
		)
		(fp_line
			(start 0.120396 0.2794)
			(end -0.12065 0.2794)
			(stroke
				(width 0.1)
				(type default)
			)
			(layer "F.Fab")
		)
		(fp_line
			(start -0.12065 0.2794)
			(end -0.12065 0.3048)
			(stroke
				(width 0.1)
				(type default)
			)
			(layer "F.Fab")
		)
		(fp_line
			(start 0.67945 0.3048)
			(end 0.120396 0.3048)
			(stroke
				(width 0.1)
				(type default)
			)
			(layer "F.Fab")
		)
		(fp_line
			(start 0.120396 0.3048)
			(end 0.120396 0.2794)
			(stroke
				(width 0.1)
				(type default)
			)
			(layer "F.Fab")
		)
		(fp_line
			(start -0.12065 0.3048)
			(end -0.67945 0.3048)
			(stroke
				(width 0.1)
				(type default)
			)
			(layer "F.Fab")
		)
		(fp_line
			(start -0.67945 0.3048)
			(end -0.67945 -0.305054)
			(stroke
				(width 0.1)
				(type default)
			)
			(layer "F.Fab")
		)
		(pad "1" smd circle
			(at -0.40005 0 90)
			(size 0 0)
			(layers "F.Cu" "F.Mask" "F.Paste")
			(net "P12V_SSD8")
		)
		(pad "2" smd circle
			(at 0.40005 0 90)
			(size 0 0)
			(layers "F.Cu" "F.Mask" "F.Paste")
			(net "GND")
		)
	)
)
